# S9S_MB_2U (Grand Teton) — schematic netlist excerpt (pin names and nets, part order shuffled) for the footprints in the layout excerpt that follows; sources: Cadence DE-HDL packaged netlist, KiCad conversion of 03242023_DA0F0TMBIJ0_F0T_Motherboard_J_brd_V01_OCP.brd

R2927  Q_RES  100K 1% CHIP  pkg 0402LF  page 151 : A = RST_SWB_BIC_BUF_R_N ; B = GND
R2242  Q_RES  10K 1% EMPTY  pkg 0402LF  page 195 : A = P1V05_PCH_AUX ; B = FM_BOARD_SKU_ID0

(kicad_pcb
	(version 20260206)
	(generator "pcbnew")
	(generator_version "10.0")
	(general
		(thickness 1.6)
		(legacy_teardrops no)
	)
	(paper "A4")
	(title_block
		(title "03242023_DA0F0TMBIJ0_F0T_Motherboard_J_brd_V01_OCP.brd")
		(comment 1 "Grand Teton / footprints 3088-3089 of 6105")
	)
	(layers
		(0 "F.Cu" signal "TOP")
		(4 "In1.Cu" signal "GND")
		(6 "In2.Cu" signal "IN1")
		(8 "In3.Cu" signal "GND1")
		(10 "In4.Cu" signal "IN2")
		(12 "In5.Cu" signal "GND2")
		(14 "In6.Cu" signal "IN3")
		(16 "In7.Cu" signal "GND3")
		(18 "In8.Cu" signal "VCC")
		(20 "In9.Cu" signal "VCC1")
		(22 "In10.Cu" signal "GND4")
		(24 "In11.Cu" signal "IN4")
		(26 "In12.Cu" signal "GND5")
		(28 "In13.Cu" signal "IN5")
		(30 "In14.Cu" signal "GND6")
		(32 "In15.Cu" signal "IN6")
		(34 "In16.Cu" signal "GND7")
		(2 "B.Cu" signal "BOTTOM")
		(9 "F.Adhes" user "F.Adhesive")
		(11 "B.Adhes" user "B.Adhesive")
		(13 "F.Paste" user "Package Geometry/Pastemask Top")
		(15 "B.Paste" user "Package Geometry/Pastemask Bottom")
		(5 "F.SilkS" user "Ref Des/Silkscreen Top")
		(7 "B.SilkS" user "Ref Des/Silkscreen Bottom")
		(1 "F.Mask" user "Board Geometry/Soldermask Top")
		(3 "B.Mask" user "Board Geometry/Soldermask Bottom")
		(17 "Dwgs.User" user "User.Drawings")
		(19 "Cmts.User" user "User.Comments")
		(21 "Eco1.User" user "User.Eco1")
		(23 "Eco2.User" user "User.Eco2")
		(25 "Edge.Cuts" user "Board Geometry/Outline")
		(27 "Margin" user)
		(31 "F.CrtYd" user "Package Geometry/Place Bound Top")
		(29 "B.CrtYd" user "Package Geometry/Place Bound Bottom")
		(35 "F.Fab" user "Ref Des/Assembly Top")
		(33 "B.Fab" user "Ref Des/Assembly Bottom")
	)
	(footprint ""
		(layer "F.Cu")
		(at 176.17948 -421.350948)
		(property "Reference" "R2927"
			(at 0 0 0)
			(layer "F.SilkS")
			(hide yes)
			(effects
				(font
					(size 1.27 1.27)
				)
			)
		)
		(property "Value" ""
			(at 0 0 0)
			(layer "F.Fab")
			(effects
				(font
					(size 1.27 1.27)
				)
			)
		)
		(duplicate_pad_numbers_are_jumpers no)
		(fp_line
			(start -0.7874 -0.4064)
			(end 0.7874 -0.4064)
			(stroke
				(width 0.1524)
				(type default)
			)
			(layer "F.SilkS")
		)
		(fp_line
			(start -0.7874 0.4064)
			(end -0.7874 -0.4064)
			(stroke
				(width 0.1524)
				(type default)
			)
			(layer "F.SilkS")
		)
		(fp_line
			(start 0.7874 -0.4064)
			(end 0.7874 0.4064)
			(stroke
				(width 0.1524)
				(type default)
			)
			(layer "F.SilkS")
		)
		(fp_line
			(start 0.7874 0.4064)
			(end -0.7874 0.4064)
			(stroke
				(width 0.1524)
				(type default)
			)
			(layer "F.SilkS")
		)
		(fp_line
			(start -0.67945 -0.305054)
			(end -0.12065 -0.305054)
			(stroke
				(width 0.1)
				(type default)
			)
			(layer "F.Fab")
		)
		(fp_line
			(start -0.67945 0.3048)
			(end -0.67945 -0.305054)
			(stroke
				(width 0.1)
				(type default)
			)
			(layer "F.Fab")
		)
		(fp_line
			(start -0.12065 -0.305054)
			(end -0.12065 -0.2794)
			(stroke
				(width 0.1)
				(type default)
			)
			(layer "F.Fab")
		)
		(fp_line
			(start -0.12065 -0.2794)
			(end 0.12065 -0.2794)
			(stroke
				(width 0.1)
				(type default)
			)
			(layer "F.Fab")
		)
		(fp_line
			(start -0.12065 0.2794)
			(end -0.12065 0.3048)
			(stroke
				(width 0.1)
				(type default)
			)
			(layer "F.Fab")
		)
		(fp_line
			(start -0.12065 0.3048)
			(end -0.67945 0.3048)
			(stroke
				(width 0.1)
				(type default)
			)
			(layer "F.Fab")
		)
		(fp_line
			(start 0.120396 0.2794)
			(end -0.12065 0.2794)
			(stroke
				(width 0.1)
				(type default)
			)
			(layer "F.Fab")
		)
		(fp_line
			(start 0.120396 0.3048)
			(end 0.120396 0.2794)
			(stroke
				(width 0.1)
				(type default)
			)
			(layer "F.Fab")
		)
		(fp_line
			(start 0.12065 -0.3048)
			(end 0.67945 -0.3048)
			(stroke
				(width 0.1)
				(type default)
			)
			(layer "F.Fab")
		)
		(fp_line
			(start 0.12065 -0.2794)
			(end 0.12065 -0.3048)
			(stroke
				(width 0.1)
				(type default)
			)
			(layer "F.Fab")
		)
		(fp_line
			(start 0.67945 -0.3048)
			(end 0.67945 0.3048)
			(stroke
				(width 0.1)
				(type default)
			)
			(layer "F.Fab")
		)
		(fp_line
			(start 0.67945 0.3048)
			(end 0.120396 0.3048)
			(stroke
				(width 0.1)
				(type default)
			)
			(layer "F.Fab")
		)
		(pad "1" smd circle
			(at -0.40005 0)
			(size 0 0)
			(layers "F.Cu" "F.Mask" "F.Paste")
			(net "RST_SWB_BIC_BUF_R_N")
		)
		(pad "2" smd circle
			(at 0.40005 0)
			(size 0 0)
			(layers "F.Cu" "F.Mask" "F.Paste")
			(net "GND")
		)
	)
	(footprint ""
		(layer "F.Cu")
		(at 318.8081 -76.585064 -90)
		(property "Reference" "R2242"
			(at 0 0 270)
			(layer "F.SilkS")
			(hide yes)
			(effects
				(font
					(size 1.27 1.27)
				)
			)
		)
		(property "Value" ""
			(at 0 0 270)
			(layer "F.Fab")
			(effects
				(font
					(size 1.27 1.27)
				)
			)
		)
		(duplicate_pad_numbers_are_jumpers no)
		(fp_line
			(start -0.7874 0.4064)
			(end -0.7874 -0.4064)
			(stroke
				(width 0.1524)
				(type default)
			)
			(layer "F.SilkS")
		)
		(fp_line
			(start 0.7874 0.4064)
			(end -0.7874 0.4064)
			(stroke
				(width 0.1524)
				(type default)
			)
			(layer "F.SilkS")
		)
		(fp_line
			(start -0.7874 -0.4064)
			(end 0.7874 -0.4064)
			(stroke
				(width 0.1524)
				(type default)
			)
			(layer "F.SilkS")
		)
		(fp_line
			(start 0.7874 -0.4064)
			(end 0.7874 0.4064)
			(stroke
				(width 0.1524)
				(type default)
			)
			(layer "F.SilkS")
		)
		(fp_line
			(start -0.67945 0.3048)
			(end -0.67945 -0.305054)
			(stroke
				(width 0.1)
				(type default)
			)
			(layer "F.Fab")
		)
		(fp_line
			(start -0.12065 0.3048)
			(end -0.67945 0.3048)
			(stroke
				(width 0.1)
				(type default)
			)
			(layer "F.Fab")
		)
		(fp_line
			(start 0.120396 0.3048)
			(end 0.120396 0.2794)
			(stroke
				(width 0.1)
				(type default)
			)
			(layer "F.Fab")
		)
		(fp_line
			(start 0.67945 0.3048)
			(end 0.120396 0.3048)
			(stroke
				(width 0.1)
				(type default)
			)
			(layer "F.Fab")
		)
		(fp_line
			(start -0.12065 0.2794)
			(end -0.12065 0.3048)
			(stroke
				(width 0.1)
				(type default)
			)
			(layer "F.Fab")
		)
		(fp_line
			(start 0.120396 0.2794)
			(end -0.12065 0.2794)
			(stroke
				(width 0.1)
				(type default)
			)
			(layer "F.Fab")
		)
		(fp_line
			(start -0.12065 -0.2794)
			(end 0.12065 -0.2794)
			(stroke
				(width 0.1)
				(type default)
			)
			(layer "F.Fab")
		)
		(fp_line
			(start 0.12065 -0.2794)
			(end 0.12065 -0.3048)
			(stroke
				(width 0.1)
				(type default)
			)
			(layer "F.Fab")
		)
		(fp_line
			(start 0.12065 -0.3048)
			(end 0.67945 -0.3048)
			(stroke
				(width 0.1)
				(type default)
			)
			(layer "F.Fab")
		)
		(fp_line
			(start 0.67945 -0.3048)
			(end 0.67945 0.3048)
			(stroke
				(width 0.1)
				(type default)
			)
			(layer "F.Fab")
		)
		(fp_line
			(start -0.67945 -0.305054)
			(end -0.12065 -0.305054)
			(stroke
				(width 0.1)
				(type default)
			)
			(layer "F.Fab")
		)
		(fp_line
			(start -0.12065 -0.305054)
			(end -0.12065 -0.2794)
			(stroke
				(width 0.1)
				(type default)
			)
			(layer "F.Fab")
		)
		(pad "1" smd circle
			(at -0.40005 0 270)
			(size 0 0)
			(layers "F.Cu" "F.Mask" "F.Paste")
			(net "P1V05_PCH_AUX")
		)
		(pad "2" smd circle
			(at 0.40005 0 270)
			(size 0 0)
			(layers "F.Cu" "F.Mask" "F.Paste")
			(net "FM_BOARD_SKU_ID0")
		)
	)
)
